(kicad_pcb
	(version 20260206)
	(generator "pcbnew")
	(generator_version "10.0")
	(general
		(thickness 1.6)
		(legacy_teardrops no)
	)
	(paper "A4")
	(title_block
		(title "01162023_DA0F0TEBIF0_F0T_Expander_BD_F_brd_V02_OCP.brd")
		(comment 1 "Grand Teton / footprints 6686-6690 of 9728")
	)
	(layers
		(0 "F.Cu" signal "TOP")
		(4 "In1.Cu" signal "GND")
		(6 "In2.Cu" signal "VCC")
		(8 "In3.Cu" signal "VCC1")
		(10 "In4.Cu" signal "GND1")
		(12 "In5.Cu" signal "IN1")
		(14 "In6.Cu" signal "GND2")
		(16 "In7.Cu" signal "IN2")
		(18 "In8.Cu" signal "GND3")
		(20 "In9.Cu" signal "IN3")
		(22 "In10.Cu" signal "GND4")
		(24 "In11.Cu" signal "IN4")
		(26 "In12.Cu" signal "GND5")
		(28 "In13.Cu" signal "IN5")
		(30 "In14.Cu" signal "GND6")
		(32 "In15.Cu" signal "IN6")
		(34 "In16.Cu" signal "GND7")
		(2 "B.Cu" signal "BOTTOM")
		(9 "F.Adhes" user "F.Adhesive")
		(11 "B.Adhes" user "B.Adhesive")
		(13 "F.Paste" user "Package Geometry/Pastemask Top")
		(15 "B.Paste" user "Package Geometry/Pastemask Bottom")
		(5 "F.SilkS" user "Ref Des/Silkscreen Top")
		(7 "B.SilkS" user "Ref Des/Silkscreen Bottom")
		(1 "F.Mask" user "Board Geometry/Soldermask Top")
		(3 "B.Mask" user "Board Geometry/Soldermask Bottom")
		(17 "Dwgs.User" user "User.Drawings")
		(19 "Cmts.User" user "User.Comments")
		(21 "Eco1.User" user "User.Eco1")
		(23 "Eco2.User" user "User.Eco2")
		(25 "Edge.Cuts" user "Board Geometry/Outline")
		(27 "Margin" user)
		(31 "F.CrtYd" user "Package Geometry/Place Bound Top")
		(29 "B.CrtYd" user "Package Geometry/Place Bound Bottom")
		(35 "F.Fab" user "Ref Des/Assembly Top")
		(33 "B.Fab" user "Ref Des/Assembly Bottom")
	)
	(footprint ""
		(layer "F.Cu")
		(at 19.885914 -413.969708 90)
		(property "Reference" "R5589"
			(at 0 0 90)
			(layer "F.SilkS")
			(hide yes)
			(effects
				(font
					(size 1.27 1.27)
				)
			)
		)
		(property "Value" ""
			(at 0 0 90)
			(layer "F.Fab")
			(effects
				(font
					(size 1.27 1.27)
				)
			)
		)
		(duplicate_pad_numbers_are_jumpers no)
		(fp_line
			(start 0.7874 -0.4064)
			(end 0.7874 0.4064)
			(stroke
				(width 0.1524)
				(type default)
			)
			(layer "F.SilkS")
		)
		(fp_line
			(start -0.7874 -0.4064)
			(end 0.7874 -0.4064)
			(stroke
				(width 0.1524)
				(type default)
			)
			(layer "F.SilkS")
		)
		(fp_line
			(start 0.7874 0.4064)
			(end -0.7874 0.4064)
			(stroke
				(width 0.1524)
				(type default)
			)
			(layer "F.SilkS")
		)
		(fp_line
			(start -0.7874 0.4064)
			(end -0.7874 -0.4064)
			(stroke
				(width 0.1524)
				(type default)
			)
			(layer "F.SilkS")
		)
		(fp_line
			(start -0.12065 -0.305054)
			(end -0.12065 -0.2794)
			(stroke
				(width 0.1)
				(type default)
			)
			(layer "F.Fab")
		)
		(fp_line
			(start -0.67945 -0.305054)
			(end -0.12065 -0.305054)
			(stroke
				(width 0.1)
				(type default)
			)
			(layer "F.Fab")
		)
		(fp_line
			(start 0.67945 -0.3048)
			(end 0.67945 0.3048)
			(stroke
				(width 0.1)
				(type default)
			)
			(layer "F.Fab")
		)
		(fp_line
			(start 0.12065 -0.3048)
			(end 0.67945 -0.3048)
			(stroke
				(width 0.1)
				(type default)
			)
			(layer "F.Fab")
		)
		(fp_line
			(start 0.12065 -0.2794)
			(end 0.12065 -0.3048)
			(stroke
				(width 0.1)
				(type default)
			)
			(layer "F.Fab")
		)
		(fp_line
			(start -0.12065 -0.2794)
			(end 0.12065 -0.2794)
			(stroke
				(width 0.1)
				(type default)
			)
			(layer "F.Fab")
		)
		(fp_line
			(start 0.120396 0.2794)
			(end -0.12065 0.2794)
			(stroke
				(width 0.1)
				(type default)
			)
			(layer "F.Fab")
		)
		(fp_line
			(start -0.12065 0.2794)
			(end -0.12065 0.3048)
			(stroke
				(width 0.1)
				(type default)
			)
			(layer "F.Fab")
		)
		(fp_line
			(start 0.67945 0.3048)
			(end 0.120396 0.3048)
			(stroke
				(width 0.1)
				(type default)
			)
			(layer "F.Fab")
		)
		(fp_line
			(start 0.120396 0.3048)
			(end 0.120396 0.2794)
			(stroke
				(width 0.1)
				(type default)
			)
			(layer "F.Fab")
		)
		(fp_line
			(start -0.12065 0.3048)
			(end -0.67945 0.3048)
			(stroke
				(width 0.1)
				(type default)
			)
			(layer "F.Fab")
		)
		(fp_line
			(start -0.67945 0.3048)
			(end -0.67945 -0.305054)
			(stroke
				(width 0.1)
				(type default)
			)
			(layer "F.Fab")
		)
		(pad "1" smd circle
			(at -0.40005 0 90)
			(size 0 0)
			(layers "F.Cu" "F.Mask" "F.Paste")
			(net "LM75_0_A1")
		)
		(pad "2" smd circle
			(at 0.40005 0 90)
			(size 0 0)
			(layers "F.Cu" "F.Mask" "F.Paste")
			(net "P3V3_AUX")
		)
	)
	(footprint ""
		(layer "F.Cu")
		(at 29.649674 -320.900044)
		(property "Reference" "H91"
			(at -6.35889 -8.560562 0)
			(unlocked yes)
			(layer "F.SilkS")
			(effects
				(font
					(size 0.7874 0.5842)
					(thickness 0.1524)
				)
				(justify left)
			)
		)
		(property "Value" ""
			(at 0 0 0)
			(layer "F.Fab")
			(effects
				(font
					(size 1.27 1.27)
				)
			)
		)
		(duplicate_pad_numbers_are_jumpers no)
		(fp_arc
			(start 5.723636 5.58927)
			(mid -7.409086 -3.017493)
			(end 7.999984 0)
			(stroke
				(width 0.1524)
				(type default)
			)
			(layer "F.SilkS")
		)
		(fp_arc
			(start -7.158482 -3.570986)
			(mid -5.682378 -5.630896)
			(end -3.63601 -7.125716)
			(stroke
				(width 0.1524)
				(type default)
			)
			(layer "B.SilkS")
		)
		(fp_arc
			(start -2.03708 -7.736078)
			(mid 4.550125 -6.580543)
			(end 7.957312 -0.825754)
			(stroke
				(width 0.1524)
				(type default)
			)
			(layer "B.SilkS")
		)
		(fp_arc
			(start -0.713232 7.968234)
			(mid -6.539883 4.607652)
			(end -7.74319 -2.010156)
			(stroke
				(width 0.1524)
				(type default)
			)
			(layer "B.SilkS")
		)
		(fp_arc
			(start 5.242052 6.043168)
			(mid 3.165825 7.347029)
			(end 0.792226 7.960868)
			(stroke
				(width 0.1524)
				(type default)
			)
			(layer "B.SilkS")
		)
		(fp_circle
			(center 0 0)
			(end 7.999984 0)
			(stroke
				(width 0.1)
				(type default)
			)
			(fill no)
			(layer "B.Fab")
		)
		(fp_circle
			(center 0 0)
			(end 7.999984 0)
			(stroke
				(width 0.1)
				(type default)
			)
			(fill no)
			(layer "F.Fab")
		)
		(pad "" np_thru_hole circle
			(at 0 0)
			(size 4.5212 4.5212)
			(drill 4.5212)
			(layers "*.Cu" "*.Mask")
			(clearance 0.381)
			(thermal_gap 0.381)
		)
		(pad "2" thru_hole circle
			(at 3.6322 0)
			(size 0.762 0.762)
			(drill 0.5588)
			(layers "*.Cu" "*.Mask")
			(remove_unused_layers no)
			(net "GND")
			(clearance 0.1524)
			(thermal_gap 0.1524)
		)
		(pad "3" thru_hole circle
			(at 2.568448 -2.568448)
			(size 0.762 0.762)
			(drill 0.5588)
			(layers "*.Cu" "*.Mask")
			(remove_unused_layers no)
			(net "GND")
			(clearance 0.1524)
			(thermal_gap 0.1524)
		)
		(pad "4" thru_hole circle
			(at 0 -3.6322)
			(size 0.762 0.762)
			(drill 0.5588)
			(layers "*.Cu" "*.Mask")
			(remove_unused_layers no)
			(net "GND")
			(clearance 0.1524)
			(thermal_gap 0.1524)
		)
		(pad "5" thru_hole circle
			(at -2.568448 -2.568448)
			(size 0.762 0.762)
			(drill 0.5588)
			(layers "*.Cu" "*.Mask")
			(remove_unused_layers no)
			(net "GND")
			(clearance 0.1524)
			(thermal_gap 0.1524)
		)
		(pad "6" thru_hole circle
			(at -3.6322 0)
			(size 0.762 0.762)
			(drill 0.5588)
			(layers "*.Cu" "*.Mask")
			(remove_unused_layers no)
			(net "GND")
			(clearance 0.1524)
			(thermal_gap 0.1524)
		)
		(pad "7" thru_hole circle
			(at -2.568448 2.568448)
			(size 0.762 0.762)
			(drill 0.5588)
			(layers "*.Cu" "*.Mask")
			(remove_unused_layers no)
			(net "GND")
			(clearance 0.1524)
			(thermal_gap 0.1524)
		)
		(pad "8" thru_hole circle
			(at 0 3.6322)
			(size 0.762 0.762)
			(drill 0.5588)
			(layers "*.Cu" "*.Mask")
			(remove_unused_layers no)
			(net "GND")
			(clearance 0.1524)
			(thermal_gap 0.1524)
		)
		(pad "9" thru_hole circle
			(at 2.568448 2.568448)
			(size 0.762 0.762)
			(drill 0.5588)
			(layers "*.Cu" "*.Mask")
			(remove_unused_layers no)
			(net "GND")
			(clearance 0.1524)
			(thermal_gap 0.1524)
		)
		(zone
			(layer "F.Cu")
			(hatch none 0.5)
			(connect_pads
				(clearance 0)
			)
			(min_thickness 0.25)
			(keepout
				(tracks not_allowed)
				(vias allowed)
				(pads allowed)
				(copperpour not_allowed)
				(footprints allowed)
			)
			(placement
				(enabled no)
				(sheetname "")
			)
			(fill
				(thermal_gap 0.5)
				(thermal_bridge_width 0.5)
				(island_removal_mode 0)
			)
			(polygon
				(pts
					(arc
						(start 29.649674 -312.90006)
						(mid 21.64969 -320.900044)
						(end 29.649674 -328.900028)
					)
					(arc
						(start 29.649674 -325.649844)
						(mid 24.899874 -320.900044)
						(end 29.649674 -316.150244)
					)
				)
			)
		)
		(zone
			(layer "F.Cu")
			(hatch none 0.5)
			(connect_pads
				(clearance 0)
			)
			(min_thickness 0.25)
			(keepout
				(tracks not_allowed)
				(vias allowed)
				(pads allowed)
				(copperpour not_allowed)
				(footprints allowed)
			)
			(placement
				(enabled no)
				(sheetname "")
			)
			(fill
				(thermal_gap 0.5)
				(thermal_bridge_width 0.5)
				(island_removal_mode 0)
			)
			(polygon
				(pts
					(arc
						(start 29.649674 -312.90006)
						(mid 37.649658 -320.900044)
						(end 29.649674 -328.900028)
					)
					(arc
						(start 29.649674 -325.649844)
						(mid 34.399474 -320.900044)
						(end 29.649674 -316.150244)
					)
				)
			)
		)
		(zone
			(layers "F.Cu" "B.Cu" "In1.Cu" "In2.Cu" "In3.Cu" "In4.Cu" "In5.Cu" "In6.Cu"
				"In7.Cu" "In8.Cu" "In9.Cu" "In10.Cu" "In11.Cu" "In12.Cu" "In13.Cu" "In14.Cu"
				"In15.Cu" "In16.Cu"
			)
			(hatch none 0.5)
			(connect_pads
				(clearance 0)
			)
			(min_thickness 0.25)
			(keepout
				(tracks not_allowed)
				(vias allowed)
				(pads allowed)
				(copperpour not_allowed)
				(footprints allowed)
			)
			(placement
				(enabled no)
				(sheetname "")
			)
			(fill
				(thermal_gap 0.5)
				(thermal_bridge_width 0.5)
				(island_removal_mode 0)
			)
			(polygon
				(pts
					(arc
						(start 32.415734 -320.900044)
						(mid 26.883614 -320.900044)
						(end 32.415734 -320.900044)
					)
				)
			)
		)
		(zone
			(layer "B.Cu")
			(hatch none 0.5)
			(connect_pads
				(clearance 0)
			)
			(min_thickness 0.25)
			(keepout
				(tracks not_allowed)
				(vias allowed)
				(pads allowed)
				(copperpour not_allowed)
				(footprints allowed)
			)
			(placement
				(enabled no)
				(sheetname "")
			)
			(fill
				(thermal_gap 0.5)
				(thermal_bridge_width 0.5)
				(island_removal_mode 0)
			)
			(polygon
				(pts
					(arc
						(start 29.649674 -315.896244)
						(mid 24.645874 -320.900044)
						(end 29.649674 -325.903844)
					)
					(arc
						(start 29.649674 -325.421244)
						(mid 25.128474 -320.900044)
						(end 29.649674 -316.378844)
					)
				)
			)
		)
		(zone
			(layer "B.Cu")
			(hatch none 0.5)
			(connect_pads
				(clearance 0)
			)
			(min_thickness 0.25)
			(keepout
				(tracks not_allowed)
				(vias allowed)
				(pads allowed)
				(copperpour not_allowed)
				(footprints allowed)
			)
			(placement
				(enabled no)
				(sheetname "")
			)
			(fill
				(thermal_gap 0.5)
				(thermal_bridge_width 0.5)
				(island_removal_mode 0)
			)
			(polygon
				(pts
					(arc
						(start 29.649674 -315.896244)
						(mid 34.653474 -320.900044)
						(end 29.649674 -325.903844)
					)
					(arc
						(start 29.649674 -325.421244)
						(mid 34.170874 -320.900044)
						(end 29.649674 -316.378844)
					)
				)
			)
		)
	)
	(footprint ""
		(layer "F.Cu")
		(at 314.314332 -140.134848 -90)
		(property "Reference" "R299"
			(at 0 0 270)
			(layer "F.SilkS")
			(hide yes)
			(effects
				(font
					(size 1.27 1.27)
				)
			)
		)
		(property "Value" ""
			(at 0 0 270)
			(layer "F.Fab")
			(effects
				(font
					(size 1.27 1.27)
				)
			)
		)
		(duplicate_pad_numbers_are_jumpers no)
		(fp_line
			(start -0.7874 0.4064)
			(end -0.7874 -0.4064)
			(stroke
				(width 0.1524)
				(type default)
			)
			(layer "F.SilkS")
		)
		(fp_line
			(start 0.7874 0.4064)
			(end -0.7874 0.4064)
			(stroke
				(width 0.1524)
				(type default)
			)
			(layer "F.SilkS")
		)
		(fp_line
			(start -0.7874 -0.4064)
			(end 0.7874 -0.4064)
			(stroke
				(width 0.1524)
				(type default)
			)
			(layer "F.SilkS")
		)
		(fp_line
			(start 0.7874 -0.4064)
			(end 0.7874 0.4064)
			(stroke
				(width 0.1524)
				(type default)
			)
			(layer "F.SilkS")
		)
		(fp_line
			(start -0.67945 0.3048)
			(end -0.67945 -0.305054)
			(stroke
				(width 0.1)
				(type default)
			)
			(layer "F.Fab")
		)
		(fp_line
			(start -0.12065 0.3048)
			(end -0.67945 0.3048)
			(stroke
				(width 0.1)
				(type default)
			)
			(layer "F.Fab")
		)
		(fp_line
			(start 0.120396 0.3048)
			(end 0.120396 0.2794)
			(stroke
				(width 0.1)
				(type default)
			)
			(layer "F.Fab")
		)
		(fp_line
			(start 0.67945 0.3048)
			(end 0.120396 0.3048)
			(stroke
				(width 0.1)
				(type default)
			)
			(layer "F.Fab")
		)
		(fp_line
			(start -0.12065 0.2794)
			(end -0.12065 0.3048)
			(stroke
				(width 0.1)
				(type default)
			)
			(layer "F.Fab")
		)
		(fp_line
			(start 0.120396 0.2794)
			(end -0.12065 0.2794)
			(stroke
				(width 0.1)
				(type default)
			)
			(layer "F.Fab")
		)
		(fp_line
			(start -0.12065 -0.2794)
			(end 0.12065 -0.2794)
			(stroke
				(width 0.1)
				(type default)
			)
			(layer "F.Fab")
		)
		(fp_line
			(start 0.12065 -0.2794)
			(end 0.12065 -0.3048)
			(stroke
				(width 0.1)
				(type default)
			)
			(layer "F.Fab")
		)
		(fp_line
			(start 0.12065 -0.3048)
			(end 0.67945 -0.3048)
			(stroke
				(width 0.1)
				(type default)
			)
			(layer "F.Fab")
		)
		(fp_line
			(start 0.67945 -0.3048)
			(end 0.67945 0.3048)
			(stroke
				(width 0.1)
				(type default)
			)
			(layer "F.Fab")
		)
		(fp_line
			(start -0.67945 -0.305054)
			(end -0.12065 -0.305054)
			(stroke
				(width 0.1)
				(type default)
			)
			(layer "F.Fab")
		)
		(fp_line
			(start -0.12065 -0.305054)
			(end -0.12065 -0.2794)
			(stroke
				(width 0.1)
				(type default)
			)
			(layer "F.Fab")
		)
		(pad "1" smd circle
			(at -0.40005 0 270)
			(size 0 0)
			(layers "F.Cu" "F.Mask" "F.Paste")
			(net "P3V3_AUX")
		)
		(pad "2" smd circle
			(at 0.40005 0 270)
			(size 0 0)
			(layers "F.Cu" "F.Mask" "F.Paste")
			(net "HP_NIC5_EN")
		)
	)
	(footprint ""
		(layer "F.Cu")
		(at 421.247316 -21.37156)
		(property "Reference" "C3973"
			(at 0 0 0)
			(layer "F.SilkS")
			(hide yes)
			(effects
				(font
					(size 1.27 1.27)
				)
			)
		)
		(property "Value" ""
			(at 0 0 0)
			(layer "F.Fab")
			(effects
				(font
					(size 1.27 1.27)
				)
			)
		)
		(duplicate_pad_numbers_are_jumpers no)
		(fp_line
			(start -0.7874 -0.4064)
			(end 0.7874 -0.4064)
			(stroke
				(width 0.1524)
				(type default)
			)
			(layer "F.SilkS")
		)
		(fp_line
			(start -0.7874 0.4064)
			(end -0.7874 -0.4064)
			(stroke
				(width 0.1524)
				(type default)
			)
			(layer "F.SilkS")
		)
		(fp_line
			(start 0.7874 -0.4064)
			(end 0.7874 0.4064)
			(stroke
				(width 0.1524)
				(type default)
			)
			(layer "F.SilkS")
		)
		(fp_line
			(start 0.7874 0.4064)
			(end -0.7874 0.4064)
			(stroke
				(width 0.1524)
				(type default)
			)
			(layer "F.SilkS")
		)
		(fp_line
			(start -0.67945 -0.305054)
			(end -0.12065 -0.305054)
			(stroke
				(width 0.1)
				(type default)
			)
			(layer "F.Fab")
		)
		(fp_line
			(start -0.67945 0.3048)
			(end -0.67945 -0.305054)
			(stroke
				(width 0.1)
				(type default)
			)
			(layer "F.Fab")
		)
		(fp_line
			(start -0.12065 -0.305054)
			(end -0.12065 -0.2794)
			(stroke
				(width 0.1)
				(type default)
			)
			(layer "F.Fab")
		)
		(fp_line
			(start -0.12065 -0.2794)
			(end 0.12065 -0.2794)
			(stroke
				(width 0.1)
				(type default)
			)
			(layer "F.Fab")
		)
		(fp_line
			(start -0.12065 0.2794)
			(end -0.12065 0.3048)
			(stroke
				(width 0.1)
				(type default)
			)
			(layer "F.Fab")
		)
		(fp_line
			(start -0.12065 0.3048)
			(end -0.67945 0.3048)
			(stroke
				(width 0.1)
				(type default)
			)
			(layer "F.Fab")
		)
		(fp_line
			(start 0.120396 0.2794)
			(end -0.12065 0.2794)
			(stroke
				(width 0.1)
				(type default)
			)
			(layer "F.Fab")
		)
		(fp_line
			(start 0.120396 0.3048)
			(end 0.120396 0.2794)
			(stroke
				(width 0.1)
				(type default)
			)
			(layer "F.Fab")
		)
		(fp_line
			(start 0.12065 -0.3048)
			(end 0.67945 -0.3048)
			(stroke
				(width 0.1)
				(type default)
			)
			(layer "F.Fab")
		)
		(fp_line
			(start 0.12065 -0.2794)
			(end 0.12065 -0.3048)
			(stroke
				(width 0.1)
				(type default)
			)
			(layer "F.Fab")
		)
		(fp_line
			(start 0.67945 -0.3048)
			(end 0.67945 0.3048)
			(stroke
				(width 0.1)
				(type default)
			)
			(layer "F.Fab")
		)
		(fp_line
			(start 0.67945 0.3048)
			(end 0.120396 0.3048)
			(stroke
				(width 0.1)
				(type default)
			)
			(layer "F.Fab")
		)
		(pad "1" smd circle
			(at -0.40005 0)
			(size 0 0)
			(layers "F.Cu" "F.Mask" "F.Paste")
			(net "P12V_SSD14")
		)
		(pad "2" smd circle
			(at 0.40005 0)
			(size 0 0)
			(layers "F.Cu" "F.Mask" "F.Paste")
			(net "GND")
		)
	)
	(footprint ""
		(layer "F.Cu")
		(at 116.850414 -279.486868 -90)
		(property "Reference" "PC122"
			(at 0 0 270)
			(layer "F.SilkS")
			(hide yes)
			(effects
				(font
					(size 1.27 1.27)
				)
			)
		)
		(property "Value" ""
			(at 0 0 270)
			(layer "F.Fab")
			(effects
				(font
					(size 1.27 1.27)
				)
			)
		)
		(duplicate_pad_numbers_are_jumpers no)
		(fp_line
			(start -0.7874 0.4064)
			(end -0.7874 -0.4064)
			(stroke
				(width 0.1524)
				(type default)
			)
			(layer "F.SilkS")
		)
		(fp_line
			(start 0.7874 0.4064)
			(end -0.7874 0.4064)
			(stroke
				(width 0.1524)
				(type default)
			)
			(layer "F.SilkS")
		)
		(fp_line
			(start -0.7874 -0.4064)
			(end 0.7874 -0.4064)
			(stroke
				(width 0.1524)
				(type default)
			)
			(layer "F.SilkS")
		)
		(fp_line
			(start 0.7874 -0.4064)
			(end 0.7874 0.4064)
			(stroke
				(width 0.1524)
				(type default)
			)
			(layer "F.SilkS")
		)
		(fp_line
			(start -0.67945 0.3048)
			(end -0.67945 -0.305054)
			(stroke
				(width 0.1)
				(type default)
			)
			(layer "F.Fab")
		)
		(fp_line
			(start -0.12065 0.3048)
			(end -0.67945 0.3048)
			(stroke
				(width 0.1)
				(type default)
			)
			(layer "F.Fab")
		)
		(fp_line
			(start 0.120396 0.3048)
			(end 0.120396 0.2794)
			(stroke
				(width 0.1)
				(type default)
			)
			(layer "F.Fab")
		)
		(fp_line
			(start 0.67945 0.3048)
			(end 0.120396 0.3048)
			(stroke
				(width 0.1)
				(type default)
			)
			(layer "F.Fab")
		)
		(fp_line
			(start -0.12065 0.2794)
			(end -0.12065 0.3048)
			(stroke
				(width 0.1)
				(type default)
			)
			(layer "F.Fab")
		)
		(fp_line
			(start 0.120396 0.2794)
			(end -0.12065 0.2794)
			(stroke
				(width 0.1)
				(type default)
			)
			(layer "F.Fab")
		)
		(fp_line
			(start -0.12065 -0.2794)
			(end 0.12065 -0.2794)
			(stroke
				(width 0.1)
				(type default)
			)
			(layer "F.Fab")
		)
		(fp_line
			(start 0.12065 -0.2794)
			(end 0.12065 -0.3048)
			(stroke
				(width 0.1)
				(type default)
			)
			(layer "F.Fab")
		)
		(fp_line
			(start 0.12065 -0.3048)
			(end 0.67945 -0.3048)
			(stroke
				(width 0.1)
				(type default)
			)
			(layer "F.Fab")
		)
		(fp_line
			(start 0.67945 -0.3048)
			(end 0.67945 0.3048)
			(stroke
				(width 0.1)
				(type default)
			)
			(layer "F.Fab")
		)
		(fp_line
			(start -0.67945 -0.305054)
			(end -0.12065 -0.305054)
			(stroke
				(width 0.1)
				(type default)
			)
			(layer "F.Fab")
		)
		(fp_line
			(start -0.12065 -0.305054)
			(end -0.12065 -0.2794)
			(stroke
				(width 0.1)
				(type default)
			)
			(layer "F.Fab")
		)
		(pad "1" smd circle
			(at -0.40005 0 270)
			(size 0 0)
			(layers "F.Cu" "F.Mask" "F.Paste")
			(net "P0V8_PEX0_VREF")
		)
		(pad "2" smd circle
			(at 0.40005 0 270)
			(size 0 0)
			(layers "F.Cu" "F.Mask" "F.Paste")
			(net "GND")
		)
	)
)
